# BASEBOARD_FAB2 (Tioga Pass) — schematic netlist excerpt (pin names and nets, part order shuffled) for the footprints in the layout excerpt that follows; sources: Cadence DE-HDL packaged netlist, KiCad conversion of Wiwynn_Tioga_Pass_MB.brd

TH9G1  MTG_KEYHOLE  EMPTY  pkg TH  page 195 : \1\ = GND
C3M6  CAP_A  22.0UF 4V 20% X6S  pkg 0603V  page 132 : A = PVNN_PCH_STBY ; B = GND
C5D21  CAP_A  22.0UF 4V 20% X6S  pkg 0603V  page 42 : A = PVCCMCP_CPU0 ; B = GND

(kicad_pcb
	(version 20260206)
	(generator "pcbnew")
	(generator_version "10.0")
	(general
		(thickness 1.6)
		(legacy_teardrops no)
	)
	(paper "A4")
	(title_block
		(title "Wiwynn_Tioga_Pass_MB.brd")
		(comment 1 "Tioga Pass / footprints 269-271 of 4770")
	)
	(layers
		(0 "F.Cu" signal "TOP")
		(4 "In1.Cu" signal "L2GND")
		(6 "In2.Cu" signal "L3")
		(8 "In3.Cu" signal "L4GND")
		(10 "In4.Cu" signal "L5")
		(12 "In5.Cu" signal "L6GND")
		(14 "In6.Cu" signal "L7VCC")
		(16 "In7.Cu" signal "L8VCC")
		(18 "In8.Cu" signal "L9GND")
		(20 "In9.Cu" signal "L10")
		(22 "In10.Cu" signal "L11GND")
		(24 "In11.Cu" signal "L12")
		(26 "In12.Cu" signal "L13GND")
		(2 "B.Cu" signal "BOTTOM")
		(9 "F.Adhes" user "F.Adhesive")
		(11 "B.Adhes" user "B.Adhesive")
		(13 "F.Paste" user "Package Geometry/Pastemask Top")
		(15 "B.Paste" user "Package Geometry/Pastemask Bottom")
		(5 "F.SilkS" user "Ref Des/Silkscreen Top")
		(7 "B.SilkS" user "Ref Des/Silkscreen Bottom")
		(1 "F.Mask" user "Board Geometry/Soldermask Top")
		(3 "B.Mask" user "Board Geometry/Soldermask Bottom")
		(17 "Dwgs.User" user "User.Drawings")
		(19 "Cmts.User" user "User.Comments")
		(21 "Eco1.User" user "User.Eco1")
		(23 "Eco2.User" user "User.Eco2")
		(25 "Edge.Cuts" user "Board Geometry/Outline")
		(27 "Margin" user)
		(31 "F.CrtYd" user "Package Geometry/Place Bound Top")
		(29 "B.CrtYd" user "Package Geometry/Place Bound Bottom")
		(35 "F.Fab" user "Ref Des/Assembly Top")
		(33 "B.Fab" user "Ref Des/Assembly Bottom")
	)
	(footprint ""
		(layer "F.Cu")
		(at 381.4572 -141.7447 90)
		(property "Reference" "C3M6"
			(at 0 0 90)
			(layer "F.SilkS")
			(hide yes)
			(effects
				(font
					(size 1.27 1.27)
				)
			)
		)
		(property "Value" ""
			(at 0 0 90)
			(layer "F.Fab")
			(effects
				(font
					(size 1.27 1.27)
				)
			)
		)
		(duplicate_pad_numbers_are_jumpers no)
		(fp_rect
			(start -0.4953 -0.2032)
			(end 0.4953 1.6002)
			(stroke
				(width 0)
				(type default)
			)
			(fill no)
			(layer "F.CrtYd")
		)
		(fp_line
			(start 0.4953 -0.2032)
			(end 0.4953 1.6002)
			(stroke
				(width 0.1)
				(type default)
			)
			(layer "F.Fab")
		)
		(fp_line
			(start -0.4953 -0.2032)
			(end 0.4953 -0.2032)
			(stroke
				(width 0.1)
				(type default)
			)
			(layer "F.Fab")
		)
		(fp_line
			(start 0.4953 1.6002)
			(end -0.4953 1.6002)
			(stroke
				(width 0.1)
				(type default)
			)
			(layer "F.Fab")
		)
		(fp_line
			(start -0.4953 1.6002)
			(end -0.4953 -0.2032)
			(stroke
				(width 0.1)
				(type default)
			)
			(layer "F.Fab")
		)
		(pad "1" smd rect
			(at 0 0 90)
			(size 0.762 0.889)
			(layers "F.Cu" "F.Mask" "F.Paste")
			(net "PVNN_PCH_STBY")
		)
		(pad "2" smd rect
			(at 0 1.397 90)
			(size 0.762 0.889)
			(layers "F.Cu" "F.Mask" "F.Paste")
			(net "GND")
		)
		(zone
			(layer "F.Cu")
			(hatch none 0.5)
			(connect_pads
				(clearance 0)
			)
			(min_thickness 0.25)
			(keepout
				(tracks not_allowed)
				(vias allowed)
				(pads allowed)
				(copperpour not_allowed)
				(footprints allowed)
			)
			(placement
				(enabled no)
				(sheetname "")
			)
			(fill
				(thermal_gap 0.5)
				(thermal_bridge_width 0.5)
				(island_removal_mode 0)
			)
			(polygon
				(pts
					(xy 381.9017 -141.3637) (xy 382.4097 -141.3637) (xy 382.4097 -142.1257) (xy 381.9017 -142.1257)
				)
			)
		)
	)
	(footprint ""
		(layer "F.Cu")
		(at 471.000074 1.999996 90)
		(property "Reference" "TH9G1"
			(at 4.640326 1.820926 0)
			(unlocked yes)
			(layer "F.SilkS")
			(effects
				(font
					(size 0.7874 0.5842)
					(thickness 0.1524)
				)
				(justify left)
			)
		)
		(property "Value" ""
			(at 0 0 90)
			(layer "F.Fab")
			(effects
				(font
					(size 1.27 1.27)
				)
			)
		)
		(duplicate_pad_numbers_are_jumpers no)
		(fp_poly
			(pts
				(arc
					(start 3.0226 0.68834)
					(mid 3.042235 0.827855)
					(end 3.099562 0.956564)
				)
				(arc
					(start 3.099562 0.956564)
					(mid 4.012804 3.550073)
					(end 3.042158 6.12267)
				)
				(arc
					(start 3.042158 6.12267)
					(mid 0 7.518589)
					(end -3.042158 6.12267)
				)
				(arc
					(start -3.042158 6.12267)
					(mid -4.012854 3.55061)
					(end -3.100324 0.957326)
				)
				(arc
					(start -3.100324 0.957326)
					(mid -3.042498 0.827518)
					(end -3.0226 0.686816)
				)
				(arc
					(start -3.0226 -0.000254)
					(mid -2.137121 -2.137227)
					(end 0 -3.022346)
				)
				(arc
					(start 0 -3.022346)
					(mid 2.137227 -2.136973)
					(end 3.0226 0.000254)
				)
			)
			(stroke
				(width 0)
				(type default)
			)
			(fill no)
			(layer "F.CrtYd")
		)
		(pad "1" thru_hole custom
			(at 0 0 90)
			(size 2.00667 2.00667)
			(drill 0.3048)
			(layers "*.Cu" "*.Mask")
			(remove_unused_layers no)
			(net "GND")
			(clearance -0.889)
			(options
				(clearance outline)
				(anchor circle)
			)
			(primitives
				(gr_poly
					(pts
						(arc
							(start 3.042158 3.874516)
							(mid 0 5.270435)
							(end -3.042158 3.874516)
						)
						(arc
							(start -3.042158 3.874516)
							(mid -4.012854 1.302456)
							(end -3.100324 -1.290828)
						)
						(arc
							(start -3.100324 -1.290828)
							(mid -3.042498 -1.420636)
							(end -3.0226 -1.561338)
						)
						(arc
							(start -3.0226 -2.248408)
							(mid -2.137121 -4.385381)
							(end 0 -5.2705)
						)
						(arc
							(start 0 -5.2705)
							(mid 2.137227 -4.385127)
							(end 3.0226 -2.2479)
						)
						(arc
							(start 3.0226 -1.55956)
							(mid 3.04227 -1.420177)
							(end 3.099562 -1.29159)
						)
						(arc
							(start 3.099562 -1.29159)
							(mid 4.012804 1.301919)
							(end 3.042158 3.874516)
						)
					)
					(width 0)
					(fill yes)
				)
			)
		)
	)
	(footprint ""
		(layer "F.Cu")
		(at 273.2532 -79.6036 180)
		(property "Reference" "C5D21"
			(at 0 0 180)
			(layer "F.SilkS")
			(hide yes)
			(effects
				(font
					(size 1.27 1.27)
				)
			)
		)
		(property "Value" ""
			(at 0 0 180)
			(layer "F.Fab")
			(effects
				(font
					(size 1.27 1.27)
				)
			)
		)
		(duplicate_pad_numbers_are_jumpers no)
		(fp_poly
			(pts
				(xy -0.4953 -0.2032) (xy 0.4953 -0.2032) (xy 0.4953 1.6002) (xy -0.4953 1.6002)
			)
			(stroke
				(width 0)
				(type default)
			)
			(fill no)
			(layer "F.CrtYd")
		)
		(fp_line
			(start 0.4953 1.6002)
			(end -0.4953 1.6002)
			(stroke
				(width 0.1)
				(type default)
			)
			(layer "F.Fab")
		)
		(fp_line
			(start 0.4953 -0.2032)
			(end 0.4953 1.6002)
			(stroke
				(width 0.1)
				(type default)
			)
			(layer "F.Fab")
		)
		(fp_line
			(start -0.4953 1.6002)
			(end -0.4953 -0.2032)
			(stroke
				(width 0.1)
				(type default)
			)
			(layer "F.Fab")
		)
		(fp_line
			(start -0.4953 -0.2032)
			(end 0.4953 -0.2032)
			(stroke
				(width 0.1)
				(type default)
			)
			(layer "F.Fab")
		)
		(pad "1" smd rect
			(at 0 0 180)
			(size 0.762 0.889)
			(layers "F.Cu" "F.Mask" "F.Paste")
			(net "PVCCMCP_CPU0")
		)
		(pad "2" smd rect
			(at 0 1.397 180)
			(size 0.762 0.889)
			(layers "F.Cu" "F.Mask" "F.Paste")
			(net "GND")
		)
		(zone
			(layer "F.Cu")
			(hatch none 0.5)
			(connect_pads
				(clearance 0)
			)
			(min_thickness 0.25)
			(keepout
				(tracks not_allowed)
				(vias allowed)
				(pads allowed)
				(copperpour not_allowed)
				(footprints allowed)
			)
			(placement
				(enabled no)
				(sheetname "")
			)
			(fill
				(thermal_gap 0.5)
				(thermal_bridge_width 0.5)
				(island_removal_mode 0)
			)
			(polygon
				(pts
					(xy 273.6342 -80.0481) (xy 272.8722 -80.0481) (xy 272.8722 -80.5561) (xy 273.6342 -80.5561)
				)
			)
		)
	)
)
